(kicad_pcb
	(version 20241229)
	(generator "pcbnew")
	(generator_version "9.0")
	(general
		(thickness 1.599998)
		(legacy_teardrops no)
	)
	(paper "A4")
	(title_block
		(title "Artix - Datacenter Secure Control Module (DC-SCM)")
		(date "2024-11-06")
		(rev "1.1.3")
		(comment 9 "footprints 533-538 of 544")
	)
	(layers
		(0 "F.Cu" signal)
		(4 "In1.Cu" signal)
		(6 "In2.Cu" signal)
		(8 "In3.Cu" signal)
		(10 "In4.Cu" signal)
		(12 "In5.Cu" signal)
		(14 "In6.Cu" signal)
		(2 "B.Cu" signal)
		(9 "F.Adhes" user "F.Adhesive")
		(11 "B.Adhes" user "B.Adhesive")
		(13 "F.Paste" user)
		(15 "B.Paste" user)
		(5 "F.SilkS" user "F.Silkscreen")
		(7 "B.SilkS" user "B.Silkscreen")
		(1 "F.Mask" user)
		(3 "B.Mask" user)
		(17 "Dwgs.User" user "User.Drawings")
		(19 "Cmts.User" user "User.Comments")
		(21 "Eco1.User" user "User.Eco1")
		(23 "Eco2.User" user "User.Eco2")
		(25 "Edge.Cuts" user)
		(27 "Margin" user)
		(31 "F.CrtYd" user "F.Courtyard")
		(29 "B.CrtYd" user "B.Courtyard")
		(35 "F.Fab" user)
		(33 "B.Fab" user)
	)
	(footprint "antmicro-footprints:R_0402_1005Metric"
		(layer "B.Cu")
		(at 117.495 144.675)
		(descr "Resistor SMD 0402")
		(tags "resistor SMD 0402")
		(property "Reference" "R109"
			(at 0.805 0.425 0)
			(layer "B.SilkS")
			(effects
				(font
					(size 0.7 0.7)
					(thickness 0.15)
				)
				(justify right bottom mirror)
			)
		)
		(property "Value" "R_0R_0402"
			(at 0 -1.4 0)
			(layer "B.Fab")
			(effects
				(font
					(size 0.7 0.7)
					(thickness 0.15)
				)
				(justify right bottom mirror)
			)
		)
		(property "Datasheet" "https://industrial.panasonic.com/cdbs/www-data/pdf/RDA0000/AOA0000C301.pdf"
			(at 0 0 0)
			(layer "F.Fab")
			(hide yes)
			(effects
				(font
					(size 1.27 1.27)
					(thickness 0.15)
				)
			)
		)
		(property "Description" "SMD Chip Resistor, Jumper, 0 ohm, 100 mW, 0402 [1005 Metric], Thick Film, General Purpose"
			(at 0 0 0)
			(layer "F.Fab")
			(hide yes)
			(effects
				(font
					(size 1.27 1.27)
					(thickness 0.15)
				)
			)
		)
		(property "Author" "Antmicro"
			(at 0 0 0)
			(layer "B.Fab")
			(hide yes)
			(effects
				(font
					(size 1 1)
					(thickness 0.15)
				)
				(justify mirror)
			)
		)
		(property "Current" "1A"
			(at 0 0 0)
			(layer "B.Fab")
			(hide yes)
			(effects
				(font
					(size 1 1)
					(thickness 0.15)
				)
				(justify mirror)
			)
		)
		(property "License" "Apache-2.0"
			(at 0 0 0)
			(layer "B.Fab")
			(hide yes)
			(effects
				(font
					(size 1 1)
					(thickness 0.15)
				)
				(justify mirror)
			)
		)
		(property "MPN" "ERJ2GE0R00X"
			(at 0 0 0)
			(layer "B.Fab")
			(hide yes)
			(effects
				(font
					(size 1 1)
					(thickness 0.15)
				)
				(justify mirror)
			)
		)
		(property "Manufacturer" "Panasonic"
			(at 0 0 0)
			(layer "B.Fab")
			(hide yes)
			(effects
				(font
					(size 1 1)
					(thickness 0.15)
				)
				(justify mirror)
			)
		)
		(property "Tolerance" "~"
			(at 0 0 0)
			(layer "B.Fab")
			(hide yes)
			(effects
				(font
					(size 1 1)
					(thickness 0.15)
				)
				(justify mirror)
			)
		)
		(property "Val" "0R"
			(at 0 0 0)
			(layer "B.Fab")
			(hide yes)
			(effects
				(font
					(size 1 1)
					(thickness 0.15)
				)
				(justify mirror)
			)
		)
		(sheetname "/Edge connector/")
		(sheetfile "edge-connector.kicad_sch")
		(attr smd)
		(fp_rect
			(start -0.925 0.47)
			(end 0.925 -0.47)
			(stroke
				(width 0.05)
				(type default)
			)
			(fill no)
			(layer "B.CrtYd")
		)
		(fp_rect
			(start -0.5 0.25)
			(end 0.5 -0.25)
			(stroke
				(width 0.15)
				(type solid)
			)
			(fill no)
			(layer "B.Fab")
		)
		(pad "1" smd roundrect
			(at -0.48 0)
			(size 0.59 0.64)
			(layers "B.Cu" "B.Mask" "B.Paste")
			(roundrect_rratio 0.25)
			(net 395 "RoT_CPU_RST_N_R")
			(pintype "passive")
		)
		(pad "2" smd roundrect
			(at 0.48 0)
			(size 0.59 0.64)
			(layers "B.Cu" "B.Mask" "B.Paste")
			(roundrect_rratio 0.25)
			(net 250 "/Edge connector/RoT_CPU_RST_N")
			(pintype "passive")
		)
	)
	(footprint "antmicro-footprints:R_0402_1005Metric"
		(layer "B.Cu")
		(at 117.495 147.675)
		(descr "Resistor SMD 0402")
		(tags "resistor SMD 0402")
		(property "Reference" "R106"
			(at 0.805 0.425 0)
			(layer "B.SilkS")
			(effects
				(font
					(size 0.7 0.7)
					(thickness 0.15)
				)
				(justify right bottom mirror)
			)
		)
		(property "Value" "R_0R_0402"
			(at 0 -1.4 0)
			(layer "B.Fab")
			(effects
				(font
					(size 0.7 0.7)
					(thickness 0.15)
				)
				(justify right bottom mirror)
			)
		)
		(property "Datasheet" "https://industrial.panasonic.com/cdbs/www-data/pdf/RDA0000/AOA0000C301.pdf"
			(at 0 0 0)
			(layer "F.Fab")
			(hide yes)
			(effects
				(font
					(size 1.27 1.27)
					(thickness 0.15)
				)
			)
		)
		(property "Description" "SMD Chip Resistor, Jumper, 0 ohm, 100 mW, 0402 [1005 Metric], Thick Film, General Purpose"
			(at 0 0 0)
			(layer "F.Fab")
			(hide yes)
			(effects
				(font
					(size 1.27 1.27)
					(thickness 0.15)
				)
			)
		)
		(property "Author" "Antmicro"
			(at 0 0 0)
			(layer "B.Fab")
			(hide yes)
			(effects
				(font
					(size 1 1)
					(thickness 0.15)
				)
				(justify mirror)
			)
		)
		(property "Current" "1A"
			(at 0 0 0)
			(layer "B.Fab")
			(hide yes)
			(effects
				(font
					(size 1 1)
					(thickness 0.15)
				)
				(justify mirror)
			)
		)
		(property "License" "Apache-2.0"
			(at 0 0 0)
			(layer "B.Fab")
			(hide yes)
			(effects
				(font
					(size 1 1)
					(thickness 0.15)
				)
				(justify mirror)
			)
		)
		(property "MPN" "ERJ2GE0R00X"
			(at 0 0 0)
			(layer "B.Fab")
			(hide yes)
			(effects
				(font
					(size 1 1)
					(thickness 0.15)
				)
				(justify mirror)
			)
		)
		(property "Manufacturer" "Panasonic"
			(at 0 0 0)
			(layer "B.Fab")
			(hide yes)
			(effects
				(font
					(size 1 1)
					(thickness 0.15)
				)
				(justify mirror)
			)
		)
		(property "Tolerance" "~"
			(at 0 0 0)
			(layer "B.Fab")
			(hide yes)
			(effects
				(font
					(size 1 1)
					(thickness 0.15)
				)
				(justify mirror)
			)
		)
		(property "Val" "0R"
			(at 0 0 0)
			(layer "B.Fab")
			(hide yes)
			(effects
				(font
					(size 1 1)
					(thickness 0.15)
				)
				(justify mirror)
			)
		)
		(sheetname "/Edge connector/")
		(sheetfile "edge-connector.kicad_sch")
		(attr smd)
		(fp_rect
			(start -0.925 0.47)
			(end 0.925 -0.47)
			(stroke
				(width 0.05)
				(type default)
			)
			(fill no)
			(layer "B.CrtYd")
		)
		(fp_rect
			(start -0.5 0.25)
			(end 0.5 -0.25)
			(stroke
				(width 0.15)
				(type solid)
			)
			(fill no)
			(layer "B.Fab")
		)
		(pad "1" smd roundrect
			(at -0.48 0)
			(size 0.59 0.64)
			(layers "B.Cu" "B.Mask" "B.Paste")
			(roundrect_rratio 0.25)
			(net 392 "DBP_PRDY_N_R")
			(pintype "passive")
		)
		(pad "2" smd roundrect
			(at 0.48 0)
			(size 0.59 0.64)
			(layers "B.Cu" "B.Mask" "B.Paste")
			(roundrect_rratio 0.25)
			(net 251 "/Edge connector/DBP_PRDY_N")
			(pintype "passive")
		)
	)
	(footprint "antmicro-footprints:R_0402_1005Metric"
		(layer "B.Cu")
		(at 117.495 145.675 180)
		(descr "Resistor SMD 0402")
		(tags "resistor SMD 0402")
		(property "Reference" "R108"
			(at -0.805 -0.425 0)
			(layer "B.SilkS")
			(effects
				(font
					(size 0.7 0.7)
					(thickness 0.15)
				)
				(justify right bottom mirror)
			)
		)
		(property "Value" "R_0R_0402"
			(at 0 -1.4 0)
			(layer "B.Fab")
			(effects
				(font
					(size 0.7 0.7)
					(thickness 0.15)
				)
				(justify left bottom mirror)
			)
		)
		(property "Datasheet" "https://industrial.panasonic.com/cdbs/www-data/pdf/RDA0000/AOA0000C301.pdf"
			(at 0 0 180)
			(layer "F.Fab")
			(hide yes)
			(effects
				(font
					(size 1.27 1.27)
					(thickness 0.15)
				)
			)
		)
		(property "Description" "SMD Chip Resistor, Jumper, 0 ohm, 100 mW, 0402 [1005 Metric], Thick Film, General Purpose"
			(at 0 0 180)
			(layer "F.Fab")
			(hide yes)
			(effects
				(font
					(size 1.27 1.27)
					(thickness 0.15)
				)
			)
		)
		(property "Author" "Antmicro"
			(at 234.99 291.35 0)
			(layer "B.Fab")
			(hide yes)
			(effects
				(font
					(size 1 1)
					(thickness 0.15)
				)
				(justify mirror)
			)
		)
		(property "Current" "1A"
			(at 234.99 291.35 0)
			(layer "B.Fab")
			(hide yes)
			(effects
				(font
					(size 1 1)
					(thickness 0.15)
				)
				(justify mirror)
			)
		)
		(property "License" "Apache-2.0"
			(at 234.99 291.35 0)
			(layer "B.Fab")
			(hide yes)
			(effects
				(font
					(size 1 1)
					(thickness 0.15)
				)
				(justify mirror)
			)
		)
		(property "MPN" "ERJ2GE0R00X"
			(at 234.99 291.35 0)
			(layer "B.Fab")
			(hide yes)
			(effects
				(font
					(size 1 1)
					(thickness 0.15)
				)
				(justify mirror)
			)
		)
		(property "Manufacturer" "Panasonic"
			(at 234.99 291.35 0)
			(layer "B.Fab")
			(hide yes)
			(effects
				(font
					(size 1 1)
					(thickness 0.15)
				)
				(justify mirror)
			)
		)
		(property "Tolerance" "~"
			(at 234.99 291.35 0)
			(layer "B.Fab")
			(hide yes)
			(effects
				(font
					(size 1 1)
					(thickness 0.15)
				)
				(justify mirror)
			)
		)
		(property "Val" "0R"
			(at 234.99 291.35 0)
			(layer "B.Fab")
			(hide yes)
			(effects
				(font
					(size 1 1)
					(thickness 0.15)
				)
				(justify mirror)
			)
		)
		(sheetname "/Edge connector/")
		(sheetfile "edge-connector.kicad_sch")
		(attr smd)
		(fp_rect
			(start -0.925 0.47)
			(end 0.925 -0.47)
			(stroke
				(width 0.05)
				(type default)
			)
			(fill no)
			(layer "B.CrtYd")
		)
		(fp_rect
			(start -0.5 0.25)
			(end 0.5 -0.25)
			(stroke
				(width 0.15)
				(type solid)
			)
			(fill no)
			(layer "B.Fab")
		)
		(pad "1" smd roundrect
			(at -0.48 0 180)
			(size 0.59 0.64)
			(layers "B.Cu" "B.Mask" "B.Paste")
			(roundrect_rratio 0.25)
			(net 249 "/Edge connector/SPARE1")
			(pintype "passive")
		)
		(pad "2" smd roundrect
			(at 0.48 0 180)
			(size 0.59 0.64)
			(layers "B.Cu" "B.Mask" "B.Paste")
			(roundrect_rratio 0.25)
			(net 394 "SPARE1_R")
			(pintype "passive")
		)
	)
	(footprint "antmicro-footprints:R_0402_1005Metric"
		(layer "B.Cu")
		(at 117.495 146.675)
		(descr "Resistor SMD 0402")
		(tags "resistor SMD 0402")
		(property "Reference" "R107"
			(at 0.805 0.425 0)
			(layer "B.SilkS")
			(effects
				(font
					(size 0.7 0.7)
					(thickness 0.15)
				)
				(justify right bottom mirror)
			)
		)
		(property "Value" "R_0R_0402"
			(at 0 -1.4 0)
			(layer "B.Fab")
			(effects
				(font
					(size 0.7 0.7)
					(thickness 0.15)
				)
				(justify right bottom mirror)
			)
		)
		(property "Datasheet" "https://industrial.panasonic.com/cdbs/www-data/pdf/RDA0000/AOA0000C301.pdf"
			(at 0 0 0)
			(layer "F.Fab")
			(hide yes)
			(effects
				(font
					(size 1.27 1.27)
					(thickness 0.15)
				)
			)
		)
		(property "Description" "SMD Chip Resistor, Jumper, 0 ohm, 100 mW, 0402 [1005 Metric], Thick Film, General Purpose"
			(at 0 0 0)
			(layer "F.Fab")
			(hide yes)
			(effects
				(font
					(size 1.27 1.27)
					(thickness 0.15)
				)
			)
		)
		(property "Author" "Antmicro"
			(at 0 0 0)
			(layer "B.Fab")
			(hide yes)
			(effects
				(font
					(size 1 1)
					(thickness 0.15)
				)
				(justify mirror)
			)
		)
		(property "Current" "1A"
			(at 0 0 0)
			(layer "B.Fab")
			(hide yes)
			(effects
				(font
					(size 1 1)
					(thickness 0.15)
				)
				(justify mirror)
			)
		)
		(property "License" "Apache-2.0"
			(at 0 0 0)
			(layer "B.Fab")
			(hide yes)
			(effects
				(font
					(size 1 1)
					(thickness 0.15)
				)
				(justify mirror)
			)
		)
		(property "MPN" "ERJ2GE0R00X"
			(at 0 0 0)
			(layer "B.Fab")
			(hide yes)
			(effects
				(font
					(size 1 1)
					(thickness 0.15)
				)
				(justify mirror)
			)
		)
		(property "Manufacturer" "Panasonic"
			(at 0 0 0)
			(layer "B.Fab")
			(hide yes)
			(effects
				(font
					(size 1 1)
					(thickness 0.15)
				)
				(justify mirror)
			)
		)
		(property "Tolerance" "~"
			(at 0 0 0)
			(layer "B.Fab")
			(hide yes)
			(effects
				(font
					(size 1 1)
					(thickness 0.15)
				)
				(justify mirror)
			)
		)
		(property "Val" "0R"
			(at 0 0 0)
			(layer "B.Fab")
			(hide yes)
			(effects
				(font
					(size 1 1)
					(thickness 0.15)
				)
				(justify mirror)
			)
		)
		(sheetname "/Edge connector/")
		(sheetfile "edge-connector.kicad_sch")
		(attr smd)
		(fp_rect
			(start -0.925 0.47)
			(end 0.925 -0.47)
			(stroke
				(width 0.05)
				(type default)
			)
			(fill no)
			(layer "B.CrtYd")
		)
		(fp_rect
			(start -0.5 0.25)
			(end 0.5 -0.25)
			(stroke
				(width 0.15)
				(type solid)
			)
			(fill no)
			(layer "B.Fab")
		)
		(pad "1" smd roundrect
			(at -0.48 0)
			(size 0.59 0.64)
			(layers "B.Cu" "B.Mask" "B.Paste")
			(roundrect_rratio 0.25)
			(net 393 "RST_PLTRST_BUF_N_R")
			(pintype "passive")
		)
		(pad "2" smd roundrect
			(at 0.48 0)
			(size 0.59 0.64)
			(layers "B.Cu" "B.Mask" "B.Paste")
			(roundrect_rratio 0.25)
			(net 248 "/Edge connector/RST_PLTRST_BUF_N")
			(pintype "passive")
		)
	)
	(footprint "antmicro-footprints:R_0402_1005Metric"
		(layer "B.Cu")
		(at 117.495 141.675)
		(descr "Resistor SMD 0402")
		(tags "resistor SMD 0402")
		(property "Reference" "R112"
			(at 0.805 0.425 0)
			(layer "B.SilkS")
			(effects
				(font
					(size 0.7 0.7)
					(thickness 0.15)
				)
				(justify right bottom mirror)
			)
		)
		(property "Value" "R_0R_0402"
			(at 0 -1.4 0)
			(layer "B.Fab")
			(effects
				(font
					(size 0.7 0.7)
					(thickness 0.15)
				)
				(justify right bottom mirror)
			)
		)
		(property "Datasheet" "https://industrial.panasonic.com/cdbs/www-data/pdf/RDA0000/AOA0000C301.pdf"
			(at 0 0 0)
			(layer "F.Fab")
			(hide yes)
			(effects
				(font
					(size 1.27 1.27)
					(thickness 0.15)
				)
			)
		)
		(property "Description" "SMD Chip Resistor, Jumper, 0 ohm, 100 mW, 0402 [1005 Metric], Thick Film, General Purpose"
			(at 0 0 0)
			(layer "F.Fab")
			(hide yes)
			(effects
				(font
					(size 1.27 1.27)
					(thickness 0.15)
				)
			)
		)
		(property "Author" "Antmicro"
			(at 0 0 0)
			(layer "B.Fab")
			(hide yes)
			(effects
				(font
					(size 1 1)
					(thickness 0.15)
				)
				(justify mirror)
			)
		)
		(property "Current" "1A"
			(at 0 0 0)
			(layer "B.Fab")
			(hide yes)
			(effects
				(font
					(size 1 1)
					(thickness 0.15)
				)
				(justify mirror)
			)
		)
		(property "License" "Apache-2.0"
			(at 0 0 0)
			(layer "B.Fab")
			(hide yes)
			(effects
				(font
					(size 1 1)
					(thickness 0.15)
				)
				(justify mirror)
			)
		)
		(property "MPN" "ERJ2GE0R00X"
			(at 0 0 0)
			(layer "B.Fab")
			(hide yes)
			(effects
				(font
					(size 1 1)
					(thickness 0.15)
				)
				(justify mirror)
			)
		)
		(property "Manufacturer" "Panasonic"
			(at 0 0 0)
			(layer "B.Fab")
			(hide yes)
			(effects
				(font
					(size 1 1)
					(thickness 0.15)
				)
				(justify mirror)
			)
		)
		(property "Tolerance" "~"
			(at 0 0 0)
			(layer "B.Fab")
			(hide yes)
			(effects
				(font
					(size 1 1)
					(thickness 0.15)
				)
				(justify mirror)
			)
		)
		(property "Val" "0R"
			(at 0 0 0)
			(layer "B.Fab")
			(hide yes)
			(effects
				(font
					(size 1 1)
					(thickness 0.15)
				)
				(justify mirror)
			)
		)
		(sheetname "/Edge connector/")
		(sheetfile "edge-connector.kicad_sch")
		(attr smd)
		(fp_rect
			(start -0.925 0.47)
			(end 0.925 -0.47)
			(stroke
				(width 0.05)
				(type default)
			)
			(fill no)
			(layer "B.CrtYd")
		)
		(fp_rect
			(start -0.5 0.25)
			(end 0.5 -0.25)
			(stroke
				(width 0.15)
				(type solid)
			)
			(fill no)
			(layer "B.Fab")
		)
		(pad "1" smd roundrect
			(at -0.48 0)
			(size 0.59 0.64)
			(layers "B.Cu" "B.Mask" "B.Paste")
			(roundrect_rratio 0.25)
			(net 398 "IRQ_N_R")
			(pintype "passive")
		)
		(pad "2" smd roundrect
			(at 0.48 0)
			(size 0.59 0.64)
			(layers "B.Cu" "B.Mask" "B.Paste")
			(roundrect_rratio 0.25)
			(net 245 "/Edge connector/IRQ_N")
			(pintype "passive")
		)
	)
	(footprint "antmicro-footprints:R_0402_1005Metric"
		(layer "B.Cu")
		(at 117.495 143.675 180)
		(descr "Resistor SMD 0402")
		(tags "resistor SMD 0402")
		(property "Reference" "R110"
			(at -0.805 -0.425 0)
			(layer "B.SilkS")
			(effects
				(font
					(size 0.7 0.7)
					(thickness 0.15)
				)
				(justify right bottom mirror)
			)
		)
		(property "Value" "R_0R_0402"
			(at 0 -1.4 0)
			(layer "B.Fab")
			(effects
				(font
					(size 0.7 0.7)
					(thickness 0.15)
				)
				(justify left bottom mirror)
			)
		)
		(property "Datasheet" "https://industrial.panasonic.com/cdbs/www-data/pdf/RDA0000/AOA0000C301.pdf"
			(at 0 0 180)
			(layer "F.Fab")
			(hide yes)
			(effects
				(font
					(size 1.27 1.27)
					(thickness 0.15)
				)
			)
		)
		(property "Description" "SMD Chip Resistor, Jumper, 0 ohm, 100 mW, 0402 [1005 Metric], Thick Film, General Purpose"
			(at 0 0 180)
			(layer "F.Fab")
			(hide yes)
			(effects
				(font
					(size 1.27 1.27)
					(thickness 0.15)
				)
			)
		)
		(property "Author" "Antmicro"
			(at 234.99 287.35 0)
			(layer "B.Fab")
			(hide yes)
			(effects
				(font
					(size 1 1)
					(thickness 0.15)
				)
				(justify mirror)
			)
		)
		(property "Current" "1A"
			(at 234.99 287.35 0)
			(layer "B.Fab")
			(hide yes)
			(effects
				(font
					(size 1 1)
					(thickness 0.15)
				)
				(justify mirror)
			)
		)
		(property "License" "Apache-2.0"
			(at 234.99 287.35 0)
			(layer "B.Fab")
			(hide yes)
			(effects
				(font
					(size 1 1)
					(thickness 0.15)
				)
				(justify mirror)
			)
		)
		(property "MPN" "ERJ2GE0R00X"
			(at 234.99 287.35 0)
			(layer "B.Fab")
			(hide yes)
			(effects
				(font
					(size 1 1)
					(thickness 0.15)
				)
				(justify mirror)
			)
		)
		(property "Manufacturer" "Panasonic"
			(at 234.99 287.35 0)
			(layer "B.Fab")
			(hide yes)
			(effects
				(font
					(size 1 1)
					(thickness 0.15)
				)
				(justify mirror)
			)
		)
		(property "Tolerance" "~"
			(at 234.99 287.35 0)
			(layer "B.Fab")
			(hide yes)
			(effects
				(font
					(size 1 1)
					(thickness 0.15)
				)
				(justify mirror)
			)
		)
		(property "Val" "0R"
			(at 234.99 287.35 0)
			(layer "B.Fab")
			(hide yes)
			(effects
				(font
					(size 1 1)
					(thickness 0.15)
				)
				(justify mirror)
			)
		)
		(sheetname "/Edge connector/")
		(sheetfile "edge-connector.kicad_sch")
		(attr smd)
		(fp_rect
			(start -0.925 0.47)
			(end 0.925 -0.47)
			(stroke
				(width 0.05)
				(type default)
			)
			(fill no)
			(layer "B.CrtYd")
		)
		(fp_rect
			(start -0.5 0.25)
			(end 0.5 -0.25)
			(stroke
				(width 0.15)
				(type solid)
			)
			(fill no)
			(layer "B.Fab")
		)
		(pad "1" smd roundrect
			(at -0.48 0 180)
			(size 0.59 0.64)
			(layers "B.Cu" "B.Mask" "B.Paste")
			(roundrect_rratio 0.25)
			(net 247 "/Edge connector/CHASI#")
			(pintype "passive")
		)
		(pad "2" smd roundrect
			(at 0.48 0 180)
			(size 0.59 0.64)
			(layers "B.Cu" "B.Mask" "B.Paste")
			(roundrect_rratio 0.25)
			(net 396 "CHASI#_R")
			(pintype "passive")
		)
	)
)
